# SCM (Grand Teton) — schematic netlist excerpt (pin names and nets, part order shuffled) for the footprints in the layout excerpt that follows; sources: Cadence DE-HDL packaged netlist, KiCad conversion of 12092022_DA0F0TMDCD0_F0T_Management_Board_D_brd_V3_OCP.brd

U53  74LVC1G08GW  IC  pkg SM  page 56
  B  = PWRGD_P5V_AUX
  A  = PWRGD_P1V2_AUX
  GND  = GND
  Y  = EN_P1V0_AUX
  VCC  = P3V3_LDO

C18  Q_CAP  0.1UF 25V 10% X7R  pkg 0402  page 20 : A = P1V2_AUX ; B = GND

(kicad_pcb
	(version 20260206)
	(generator "pcbnew")
	(generator_version "10.0")
	(general
		(thickness 1.6)
		(legacy_teardrops no)
	)
	(paper "A4")
	(title_block
		(title "12092022_DA0F0TMDCD0_F0T_Management_Board_D_brd_V3_OCP.brd")
		(comment 1 "Grand Teton / footprints 467-468 of 1440")
	)
	(layers
		(0 "F.Cu" signal "TOP")
		(4 "In1.Cu" signal "GND")
		(6 "In2.Cu" signal "IN1")
		(8 "In3.Cu" signal "GND1")
		(10 "In4.Cu" signal "IN2")
		(12 "In5.Cu" signal "VCC")
		(14 "In6.Cu" signal "VCC1")
		(16 "In7.Cu" signal "IN3")
		(18 "In8.Cu" signal "GND2")
		(20 "In9.Cu" signal "IN4")
		(22 "In10.Cu" signal "GND3")
		(2 "B.Cu" signal "BOTTOM")
		(9 "F.Adhes" user "F.Adhesive")
		(11 "B.Adhes" user "B.Adhesive")
		(13 "F.Paste" user "Package Geometry/Pastemask Top")
		(15 "B.Paste" user "Package Geometry/Pastemask Bottom")
		(5 "F.SilkS" user "Ref Des/Silkscreen Top")
		(7 "B.SilkS" user "Ref Des/Silkscreen Bottom")
		(1 "F.Mask" user "Board Geometry/Soldermask Top")
		(3 "B.Mask" user "Board Geometry/Soldermask Bottom")
		(17 "Dwgs.User" user "User.Drawings")
		(19 "Cmts.User" user "User.Comments")
		(21 "Eco1.User" user "User.Eco1")
		(23 "Eco2.User" user "User.Eco2")
		(25 "Edge.Cuts" user "Board Geometry/Outline")
		(27 "Margin" user)
		(31 "F.CrtYd" user "Package Geometry/Place Bound Top")
		(29 "B.CrtYd" user "Package Geometry/Place Bound Bottom")
		(35 "F.Fab" user "Ref Des/Assembly Top")
		(33 "B.Fab" user "Ref Des/Assembly Bottom")
	)
	(footprint ""
		(layer "F.Cu")
		(at 80.755744 -37.559488 90)
		(property "Reference" "C18"
			(at 0 0 90)
			(layer "F.SilkS")
			(hide yes)
			(effects
				(font
					(size 1.27 1.27)
				)
			)
		)
		(property "Value" ""
			(at 0 0 90)
			(layer "F.Fab")
			(effects
				(font
					(size 1.27 1.27)
				)
			)
		)
		(duplicate_pad_numbers_are_jumpers no)
		(fp_line
			(start 0.7874 -0.4064)
			(end 0.7874 0.4064)
			(stroke
				(width 0.1524)
				(type default)
			)
			(layer "F.SilkS")
		)
		(fp_line
			(start -0.7874 -0.4064)
			(end 0.7874 -0.4064)
			(stroke
				(width 0.1524)
				(type default)
			)
			(layer "F.SilkS")
		)
		(fp_line
			(start 0.7874 0.4064)
			(end -0.7874 0.4064)
			(stroke
				(width 0.1524)
				(type default)
			)
			(layer "F.SilkS")
		)
		(fp_line
			(start -0.7874 0.4064)
			(end -0.7874 -0.4064)
			(stroke
				(width 0.1524)
				(type default)
			)
			(layer "F.SilkS")
		)
		(fp_line
			(start -0.12065 -0.305054)
			(end -0.12065 -0.2794)
			(stroke
				(width 0.1)
				(type default)
			)
			(layer "F.Fab")
		)
		(fp_line
			(start -0.67945 -0.305054)
			(end -0.12065 -0.305054)
			(stroke
				(width 0.1)
				(type default)
			)
			(layer "F.Fab")
		)
		(fp_line
			(start 0.67945 -0.3048)
			(end 0.67945 0.3048)
			(stroke
				(width 0.1)
				(type default)
			)
			(layer "F.Fab")
		)
		(fp_line
			(start 0.12065 -0.3048)
			(end 0.67945 -0.3048)
			(stroke
				(width 0.1)
				(type default)
			)
			(layer "F.Fab")
		)
		(fp_line
			(start 0.12065 -0.2794)
			(end 0.12065 -0.3048)
			(stroke
				(width 0.1)
				(type default)
			)
			(layer "F.Fab")
		)
		(fp_line
			(start -0.12065 -0.2794)
			(end 0.12065 -0.2794)
			(stroke
				(width 0.1)
				(type default)
			)
			(layer "F.Fab")
		)
		(fp_line
			(start 0.120396 0.2794)
			(end -0.12065 0.2794)
			(stroke
				(width 0.1)
				(type default)
			)
			(layer "F.Fab")
		)
		(fp_line
			(start -0.12065 0.2794)
			(end -0.12065 0.3048)
			(stroke
				(width 0.1)
				(type default)
			)
			(layer "F.Fab")
		)
		(fp_line
			(start 0.67945 0.3048)
			(end 0.120396 0.3048)
			(stroke
				(width 0.1)
				(type default)
			)
			(layer "F.Fab")
		)
		(fp_line
			(start 0.120396 0.3048)
			(end 0.120396 0.2794)
			(stroke
				(width 0.1)
				(type default)
			)
			(layer "F.Fab")
		)
		(fp_line
			(start -0.12065 0.3048)
			(end -0.67945 0.3048)
			(stroke
				(width 0.1)
				(type default)
			)
			(layer "F.Fab")
		)
		(fp_line
			(start -0.67945 0.3048)
			(end -0.67945 -0.305054)
			(stroke
				(width 0.1)
				(type default)
			)
			(layer "F.Fab")
		)
		(pad "1" smd circle
			(at -0.40005 0 90)
			(size 0 0)
			(layers "F.Cu" "F.Mask" "F.Paste")
			(net "P1V2_AUX")
		)
		(pad "2" smd circle
			(at 0.40005 0 90)
			(size 0 0)
			(layers "F.Cu" "F.Mask" "F.Paste")
			(net "GND")
		)
	)
	(footprint ""
		(layer "F.Cu")
		(at 15.748 -36.7792 -90)
		(property "Reference" "U53"
			(at 3.17627 1.397 0)
			(unlocked yes)
			(layer "F.SilkS")
			(effects
				(font
					(size 0.7874 0.5842)
					(thickness 0.1524)
				)
			)
		)
		(property "Value" ""
			(at 0 0 270)
			(layer "F.Fab")
			(effects
				(font
					(size 1.27 1.27)
				)
			)
		)
		(duplicate_pad_numbers_are_jumpers no)
		(fp_line
			(start -1.7018 1.1176)
			(end -1.7018 -1.1176)
			(stroke
				(width 0.1524)
				(type default)
			)
			(layer "F.SilkS")
		)
		(fp_line
			(start 1.7018 1.1176)
			(end -1.7018 1.1176)
			(stroke
				(width 0.1524)
				(type default)
			)
			(layer "F.SilkS")
		)
		(fp_line
			(start 0 -0.7112)
			(end -0.254 -1.1176)
			(stroke
				(width 0.1524)
				(type default)
			)
			(layer "F.SilkS")
		)
		(fp_line
			(start -0.254 -1.1176)
			(end -1.7018 -1.1176)
			(stroke
				(width 0.1524)
				(type default)
			)
			(layer "F.SilkS")
		)
		(fp_line
			(start 0.254 -1.1176)
			(end 0 -0.7112)
			(stroke
				(width 0.1524)
				(type default)
			)
			(layer "F.SilkS")
		)
		(fp_line
			(start 1.7018 -1.1176)
			(end 1.7018 1.1176)
			(stroke
				(width 0.1524)
				(type default)
			)
			(layer "F.SilkS")
		)
		(fp_line
			(start 1.7018 -1.1176)
			(end 0.254 -1.1176)
			(stroke
				(width 0.1524)
				(type default)
			)
			(layer "F.SilkS")
		)
		(fp_poly
			(pts
				(xy -1.8161 -0.675386) (xy -2.4003 -0.446786) (xy -2.4003 -0.878586)
			)
			(stroke
				(width 0)
				(type default)
			)
			(fill yes)
			(layer "F.SilkS")
		)
		(fp_line
			(start -1.5494 1.1176)
			(end -1.5494 -1.1176)
			(stroke
				(width 0.1)
				(type default)
			)
			(layer "F.Fab")
		)
		(fp_line
			(start 1.5494 1.1176)
			(end -1.5494 1.1176)
			(stroke
				(width 0.1)
				(type default)
			)
			(layer "F.Fab")
		)
		(fp_line
			(start -0.254 -1.1176)
			(end -1.5494 -1.1176)
			(stroke
				(width 0.1)
				(type default)
			)
			(layer "F.Fab")
		)
		(fp_line
			(start 0.254 -1.1176)
			(end -0.254 -1.1176)
			(stroke
				(width 0.1)
				(type default)
			)
			(layer "F.Fab")
		)
		(fp_line
			(start 1.5494 -1.1176)
			(end 1.5494 1.1176)
			(stroke
				(width 0.1)
				(type default)
			)
			(layer "F.Fab")
		)
		(fp_line
			(start 1.5494 -1.1176)
			(end 0.254 -1.1176)
			(stroke
				(width 0.1)
				(type default)
			)
			(layer "F.Fab")
		)
		(fp_poly
			(pts
				(xy -1.8161 -0.675386) (xy -2.4003 -0.446786) (xy -2.4003 -0.878586)
			)
			(stroke
				(width 0)
				(type default)
			)
			(fill yes)
			(layer "F.Fab")
		)
		(pad "1" smd rect
			(at -0.962406 -0.649986 180)
			(size 0.3302 1.1684)
			(layers "F.Cu" "F.Mask" "F.Paste")
			(net "PWRGD_P5V_AUX")
		)
		(pad "2" smd rect
			(at -0.962406 0 180)
			(size 0.3302 1.1684)
			(layers "F.Cu" "F.Mask" "F.Paste")
			(net "PWRGD_P1V2_AUX")
		)
		(pad "3" smd rect
			(at -0.962406 0.649986 180)
			(size 0.3302 1.1684)
			(layers "F.Cu" "F.Mask" "F.Paste")
			(net "GND")
		)
		(pad "4" smd rect
			(at 0.962406 0.649986 180)
			(size 0.3302 1.1684)
			(layers "F.Cu" "F.Mask" "F.Paste")
			(net "EN_P1V0_AUX")
		)
		(pad "5" smd rect
			(at 0.962406 -0.649986 180)
			(size 0.3302 1.1684)
			(layers "F.Cu" "F.Mask" "F.Paste")
			(net "P3V3_LDO")
		)
	)
)
